(kicad_pcb
	(version 20241229)
	(generator "pcbnew")
	(generator_version "9.0")
	(general
		(thickness 1.6642)
		(legacy_teardrops no)
	)
	(paper "A3")
	(title_block
		(title "PolarFire SoM")
		(date "2025-07-22")
		(rev "1.1.4")
		(company "Antmicro Ltd")
		(comment 1 "www.antmicro.com")
		(comment 9 "footprints 339-342 of 470")
	)
	(layers
		(0 "F.Cu" mixed)
		(4 "In1.Cu" power)
		(6 "In2.Cu" signal)
		(8 "In3.Cu" power)
		(10 "In4.Cu" signal)
		(12 "In5.Cu" power)
		(14 "In6.Cu" power)
		(16 "In7.Cu" signal)
		(18 "In8.Cu" power)
		(20 "In9.Cu" signal)
		(22 "In10.Cu" power)
		(24 "In11.Cu" signal)
		(26 "In12.Cu" signal)
		(2 "B.Cu" mixed)
		(9 "F.Adhes" user "F.Adhesive")
		(11 "B.Adhes" user "B.Adhesive")
		(13 "F.Paste" user)
		(15 "B.Paste" user)
		(5 "F.SilkS" user "F.Silkscreen")
		(7 "B.SilkS" user "B.Silkscreen")
		(1 "F.Mask" user)
		(3 "B.Mask" user)
		(17 "Dwgs.User" user "User.Drawings")
		(19 "Cmts.User" user "User.Comments")
		(21 "Eco1.User" user "User.Eco1")
		(23 "Eco2.User" user "User.Eco2")
		(25 "Edge.Cuts" user)
		(27 "Margin" user)
		(31 "F.CrtYd" user "F.Courtyard")
		(29 "B.CrtYd" user "B.Courtyard")
		(35 "F.Fab" user)
		(33 "B.Fab" user)
	)
	(footprint "antmicro-footprints:C_0402_1005Metric"
		(layer "B.Cu")
		(at 175.7 148.4 90)
		(descr "Capacitor SMD 0402")
		(tags "capacitor SMD 0402")
		(property "Reference" "C83"
			(at -4.15 0.25 90)
			(layer "B.SilkS")
			(effects
				(font
					(size 0.7 0.7)
					(thickness 0.15)
				)
				(justify right bottom mirror)
			)
		)
		(property "Value" "C_100n_0402"
			(at -1.022927 -2.155213 90)
			(layer "B.Fab")
			(hide yes)
			(effects
				(font
					(size 0.7 0.7)
					(thickness 0.15)
				)
				(justify right bottom mirror)
			)
		)
		(property "Datasheet" "https://www.murata.com/products/productdetail?partno=GRM155R61H104KE14%23"
			(at 0 0 90)
			(layer "F.Fab")
			(hide yes)
			(effects
				(font
					(size 1.27 1.27)
					(thickness 0.15)
				)
			)
		)
		(property "Description" "SMD Multilayer Ceramic Capacitor, 0.1 µF, 50 V, 0402 [1005 Metric], ± 10%, X5R, GRM Series"
			(at 0 0 90)
			(layer "F.Fab")
			(hide yes)
			(effects
				(font
					(size 1.27 1.27)
					(thickness 0.15)
				)
			)
		)
		(property "Author" "Antmicro"
			(at 324.1 -27.3 0)
			(layer "B.Fab")
			(hide yes)
			(effects
				(font
					(size 1 1)
					(thickness 0.15)
				)
				(justify mirror)
			)
		)
		(property "Dielectric" "X5R"
			(at 324.1 -27.3 0)
			(layer "B.Fab")
			(hide yes)
			(effects
				(font
					(size 1 1)
					(thickness 0.15)
				)
				(justify mirror)
			)
		)
		(property "License" "Apache-2.0"
			(at 324.1 -27.3 0)
			(layer "B.Fab")
			(hide yes)
			(effects
				(font
					(size 1 1)
					(thickness 0.15)
				)
				(justify mirror)
			)
		)
		(property "MPN" "GRM155R61H104KE14D"
			(at 324.1 -27.3 0)
			(layer "B.Fab")
			(hide yes)
			(effects
				(font
					(size 1 1)
					(thickness 0.15)
				)
				(justify mirror)
			)
		)
		(property "Manufacturer" "Murata"
			(at 324.1 -27.3 0)
			(layer "B.Fab")
			(hide yes)
			(effects
				(font
					(size 1 1)
					(thickness 0.15)
				)
				(justify mirror)
			)
		)
		(property "Public" ""
			(at 324.1 -27.3 0)
			(layer "B.Fab")
			(hide yes)
			(effects
				(font
					(size 1 1)
					(thickness 0.15)
				)
				(justify mirror)
			)
		)
		(property "Val" "100n"
			(at 324.1 -27.3 0)
			(layer "B.Fab")
			(hide yes)
			(effects
				(font
					(size 1 1)
					(thickness 0.15)
				)
				(justify mirror)
			)
		)
		(property "Voltage" "50V"
			(at 324.1 -27.3 0)
			(layer "B.Fab")
			(hide yes)
			(effects
				(font
					(size 1 1)
					(thickness 0.15)
				)
				(justify mirror)
			)
		)
		(sheetname "/Supply/")
		(sheetfile "supply.kicad_sch")
		(attr smd)
		(fp_rect
			(start -0.925 0.47)
			(end 0.925 -0.47)
			(stroke
				(width 0.05)
				(type default)
			)
			(fill no)
			(layer "B.CrtYd")
		)
		(fp_line
			(start 0.504 -0.248)
			(end -0.494 -0.248)
			(stroke
				(width 0.15)
				(type solid)
			)
			(layer "B.Fab")
		)
		(fp_line
			(start -0.494 -0.248)
			(end -0.494 0.25)
			(stroke
				(width 0.15)
				(type solid)
			)
			(layer "B.Fab")
		)
		(fp_line
			(start 0.504 0.25)
			(end 0.504 -0.248)
			(stroke
				(width 0.15)
				(type solid)
			)
			(layer "B.Fab")
		)
		(fp_line
			(start -0.494 0.25)
			(end 0.504 0.25)
			(stroke
				(width 0.15)
				(type solid)
			)
			(layer "B.Fab")
		)
		(fp_text user "${REFERENCE}"
			(at -0.939 -4.599 270)
			(layer "B.Fab")
			(effects
				(font
					(size 0.7 0.7)
					(thickness 0.15)
				)
				(justify left bottom mirror)
			)
		)
		(fp_text user "License: Apache-2.0"
			(at -0.939 -5.799 270)
			(layer "B.Fab")
			(effects
				(font
					(size 0.7 0.7)
					(thickness 0.15)
				)
				(justify left bottom mirror)
			)
		)
		(fp_text user "Author: Antmicro"
			(at -0.939 -3.399 270)
			(layer "B.Fab")
			(effects
				(font
					(size 0.7 0.7)
					(thickness 0.15)
				)
				(justify left bottom mirror)
			)
		)
		(pad "1" smd roundrect
			(at -0.48 0 90)
			(size 0.59 0.64)
			(layers "B.Cu" "B.Mask" "B.Paste")
			(roundrect_rratio 0.25)
			(net 417 "GND")
			(pintype "passive")
		)
		(pad "2" smd roundrect
			(at 0.48 0 90)
			(size 0.59 0.64)
			(layers "B.Cu" "B.Mask" "B.Paste")
			(roundrect_rratio 0.25)
			(net 649 "VDD")
			(pintype "passive")
		)
	)
	(footprint "antmicro-footprints:C_0402_1005Metric"
		(layer "B.Cu")
		(at 175.475 140.9675 90)
		(descr "Capacitor SMD 0402")
		(tags "capacitor SMD 0402")
		(property "Reference" "C106"
			(at 0.7975 0.255 270)
			(layer "B.SilkS")
			(effects
				(font
					(size 0.7 0.7)
					(thickness 0.15)
				)
				(justify right bottom mirror)
			)
		)
		(property "Value" "C_22u_0402"
			(at -1.022927 -2.155213 90)
			(layer "B.Fab")
			(hide yes)
			(effects
				(font
					(size 0.7 0.7)
					(thickness 0.15)
				)
				(justify right bottom mirror)
			)
		)
		(property "Datasheet" "https://www.murata.com/products/productdetail?partno=GRM158R60J226ME01%23"
			(at 0 0 90)
			(layer "F.Fab")
			(hide yes)
			(effects
				(font
					(size 1.27 1.27)
					(thickness 0.15)
				)
			)
		)
		(property "Description" "SMD Multilayer Ceramic Capacitor, 22 uF, 4 V, 0402 [1005 Metric], X6S"
			(at 0 0 90)
			(layer "F.Fab")
			(hide yes)
			(effects
				(font
					(size 1.27 1.27)
					(thickness 0.15)
				)
			)
		)
		(property "Author" "Antmicro"
			(at 316.4425 -34.5075 0)
			(layer "B.Fab")
			(hide yes)
			(effects
				(font
					(size 1 1)
					(thickness 0.15)
				)
				(justify mirror)
			)
		)
		(property "Dielectric" ""
			(at 316.4425 -34.5075 0)
			(layer "B.Fab")
			(hide yes)
			(effects
				(font
					(size 1 1)
					(thickness 0.15)
				)
				(justify mirror)
			)
		)
		(property "License" "Apache-2.0"
			(at 316.4425 -34.5075 0)
			(layer "B.Fab")
			(hide yes)
			(effects
				(font
					(size 1 1)
					(thickness 0.15)
				)
				(justify mirror)
			)
		)
		(property "MPN" "GRM158R60J226ME01D"
			(at 316.4425 -34.5075 0)
			(layer "B.Fab")
			(hide yes)
			(effects
				(font
					(size 1 1)
					(thickness 0.15)
				)
				(justify mirror)
			)
		)
		(property "Manufacturer" "Murata"
			(at 316.4425 -34.5075 0)
			(layer "B.Fab")
			(hide yes)
			(effects
				(font
					(size 1 1)
					(thickness 0.15)
				)
				(justify mirror)
			)
		)
		(property "Public" ""
			(at 316.4425 -34.5075 0)
			(layer "B.Fab")
			(hide yes)
			(effects
				(font
					(size 1 1)
					(thickness 0.15)
				)
				(justify mirror)
			)
		)
		(property "Val" "22u"
			(at 316.4425 -34.5075 0)
			(layer "B.Fab")
			(hide yes)
			(effects
				(font
					(size 1 1)
					(thickness 0.15)
				)
				(justify mirror)
			)
		)
		(property "Voltage" ""
			(at 316.4425 -34.5075 0)
			(layer "B.Fab")
			(hide yes)
			(effects
				(font
					(size 1 1)
					(thickness 0.15)
				)
				(justify mirror)
			)
		)
		(sheetname "/Supply/")
		(sheetfile "supply.kicad_sch")
		(attr smd)
		(fp_rect
			(start -0.925 0.47)
			(end 0.925 -0.47)
			(stroke
				(width 0.05)
				(type default)
			)
			(fill no)
			(layer "B.CrtYd")
		)
		(fp_line
			(start 0.504 -0.248)
			(end -0.494 -0.248)
			(stroke
				(width 0.15)
				(type solid)
			)
			(layer "B.Fab")
		)
		(fp_line
			(start -0.494 -0.248)
			(end -0.494 0.25)
			(stroke
				(width 0.15)
				(type solid)
			)
			(layer "B.Fab")
		)
		(fp_line
			(start 0.504 0.25)
			(end 0.504 -0.248)
			(stroke
				(width 0.15)
				(type solid)
			)
			(layer "B.Fab")
		)
		(fp_line
			(start -0.494 0.25)
			(end 0.504 0.25)
			(stroke
				(width 0.15)
				(type solid)
			)
			(layer "B.Fab")
		)
		(fp_text user "License: Apache-2.0"
			(at -0.939 -5.799 270)
			(layer "B.Fab")
			(effects
				(font
					(size 0.7 0.7)
					(thickness 0.15)
				)
				(justify left bottom mirror)
			)
		)
		(fp_text user "${REFERENCE}"
			(at -0.939 -4.599 270)
			(layer "B.Fab")
			(effects
				(font
					(size 0.7 0.7)
					(thickness 0.15)
				)
				(justify left bottom mirror)
			)
		)
		(fp_text user "Author: Antmicro"
			(at -0.939 -3.399 270)
			(layer "B.Fab")
			(effects
				(font
					(size 0.7 0.7)
					(thickness 0.15)
				)
				(justify left bottom mirror)
			)
		)
		(pad "1" smd roundrect
			(at -0.48 0 90)
			(size 0.59 0.64)
			(layers "B.Cu" "B.Mask" "B.Paste")
			(roundrect_rratio 0.25)
			(net 417 "GND")
			(pintype "passive")
		)
		(pad "2" smd roundrect
			(at 0.48 0 90)
			(size 0.59 0.64)
			(layers "B.Cu" "B.Mask" "B.Paste")
			(roundrect_rratio 0.25)
			(net 209 "/Supply/SENSE1_P")
			(pintype "passive")
		)
	)
	(footprint "antmicro-footprints:C_0402_1005Metric"
		(layer "B.Cu")
		(at 178.8 132.1925 180)
		(descr "Capacitor SMD 0402")
		(tags "capacitor SMD 0402")
		(property "Reference" "C265"
			(at -1.45 0.6125 0)
			(layer "B.SilkS")
			(effects
				(font
					(size 0.7 0.7)
					(thickness 0.15)
				)
				(justify left bottom mirror)
			)
		)
		(property "Value" "C_10u_0402"
			(at -1.022927 -2.155213 0)
			(layer "B.Fab")
			(hide yes)
			(effects
				(font
					(size 0.7 0.7)
					(thickness 0.15)
				)
				(justify left bottom mirror)
			)
		)
		(property "Datasheet" "https://www.yageo.com/en/Chart/Download/pdf/CC0402MRX5R5BB106"
			(at 0 0 180)
			(layer "F.Fab")
			(hide yes)
			(effects
				(font
					(size 1.27 1.27)
					(thickness 0.15)
				)
			)
		)
		(property "Description" "SMD Multilayer Ceramic Capacitor, 10 µF, 6.3 V, 0402 [1005 Metric], ± 20%, X5R, CC Series"
			(at 0 0 180)
			(layer "F.Fab")
			(hide yes)
			(effects
				(font
					(size 1.27 1.27)
					(thickness 0.15)
				)
			)
		)
		(property "Author" "Antmicro"
			(at 357.6 264.385 0)
			(layer "B.Fab")
			(hide yes)
			(effects
				(font
					(size 1 1)
					(thickness 0.15)
				)
				(justify mirror)
			)
		)
		(property "Dielectric" ""
			(at 357.6 264.385 0)
			(layer "B.Fab")
			(hide yes)
			(effects
				(font
					(size 1 1)
					(thickness 0.15)
				)
				(justify mirror)
			)
		)
		(property "License" "Apache-2.0"
			(at 357.6 264.385 0)
			(layer "B.Fab")
			(hide yes)
			(effects
				(font
					(size 1 1)
					(thickness 0.15)
				)
				(justify mirror)
			)
		)
		(property "MPN" "CC0402MRX5R5BB106"
			(at 357.6 264.385 0)
			(layer "B.Fab")
			(hide yes)
			(effects
				(font
					(size 1 1)
					(thickness 0.15)
				)
				(justify mirror)
			)
		)
		(property "Manufacturer" "YAGEO"
			(at 357.6 264.385 0)
			(layer "B.Fab")
			(hide yes)
			(effects
				(font
					(size 1 1)
					(thickness 0.15)
				)
				(justify mirror)
			)
		)
		(property "Public" ""
			(at 357.6 264.385 0)
			(layer "B.Fab")
			(hide yes)
			(effects
				(font
					(size 1 1)
					(thickness 0.15)
				)
				(justify mirror)
			)
		)
		(property "Val" "10u"
			(at 357.6 264.385 0)
			(layer "B.Fab")
			(hide yes)
			(effects
				(font
					(size 1 1)
					(thickness 0.15)
				)
				(justify mirror)
			)
		)
		(property "Voltage" ""
			(at 357.6 264.385 0)
			(layer "B.Fab")
			(hide yes)
			(effects
				(font
					(size 1 1)
					(thickness 0.15)
				)
				(justify mirror)
			)
		)
		(sheetname "/LPDDR4/")
		(sheetfile "lpddr.kicad_sch")
		(attr smd)
		(fp_rect
			(start -0.925 0.47)
			(end 0.925 -0.47)
			(stroke
				(width 0.05)
				(type default)
			)
			(fill no)
			(layer "B.CrtYd")
		)
		(fp_line
			(start 0.504 0.25)
			(end 0.504 -0.248)
			(stroke
				(width 0.15)
				(type solid)
			)
			(layer "B.Fab")
		)
		(fp_line
			(start 0.504 -0.248)
			(end -0.494 -0.248)
			(stroke
				(width 0.15)
				(type solid)
			)
			(layer "B.Fab")
		)
		(fp_line
			(start -0.494 0.25)
			(end 0.504 0.25)
			(stroke
				(width 0.15)
				(type solid)
			)
			(layer "B.Fab")
		)
		(fp_line
			(start -0.494 -0.248)
			(end -0.494 0.25)
			(stroke
				(width 0.15)
				(type solid)
			)
			(layer "B.Fab")
		)
		(fp_text user "${REFERENCE}"
			(at -0.939 -4.599 0)
			(layer "B.Fab")
			(effects
				(font
					(size 0.7 0.7)
					(thickness 0.15)
				)
				(justify left bottom mirror)
			)
		)
		(fp_text user "License: Apache-2.0"
			(at -0.939 -5.799 0)
			(layer "B.Fab")
			(effects
				(font
					(size 0.7 0.7)
					(thickness 0.15)
				)
				(justify left bottom mirror)
			)
		)
		(fp_text user "Author: Antmicro"
			(at -0.939 -3.399 0)
			(layer "B.Fab")
			(effects
				(font
					(size 0.7 0.7)
					(thickness 0.15)
				)
				(justify left bottom mirror)
			)
		)
		(pad "1" smd roundrect
			(at -0.48 0 180)
			(size 0.59 0.64)
			(layers "B.Cu" "B.Mask" "B.Paste")
			(roundrect_rratio 0.25)
			(net 417 "GND")
			(pintype "passive")
		)
		(pad "2" smd roundrect
			(at 0.48 0 180)
			(size 0.59 0.64)
			(layers "B.Cu" "B.Mask" "B.Paste")
			(roundrect_rratio 0.25)
			(net 48 "+1V8")
			(pintype "passive")
		)
	)
	(footprint "antmicro-footprints:C_0402_1005Metric"
		(layer "B.Cu")
		(at 215.329 117.56 90)
		(descr "Capacitor SMD 0402")
		(tags "capacitor SMD 0402")
		(property "Reference" "C250"
			(at -3.715 0.471 90)
			(layer "B.SilkS")
			(effects
				(font
					(size 0.7 0.7)
					(thickness 0.15)
				)
				(justify right bottom mirror)
			)
		)
		(property "Value" "C_10u_0402"
			(at -1.022927 -2.155213 90)
			(layer "B.Fab")
			(hide yes)
			(effects
				(font
					(size 0.7 0.7)
					(thickness 0.15)
				)
				(justify right bottom mirror)
			)
		)
		(property "Datasheet" "https://www.yageo.com/en/Chart/Download/pdf/CC0402MRX5R5BB106"
			(at 0 0 90)
			(layer "F.Fab")
			(hide yes)
			(effects
				(font
					(size 1.27 1.27)
					(thickness 0.15)
				)
			)
		)
		(property "Description" "SMD Multilayer Ceramic Capacitor, 10 µF, 6.3 V, 0402 [1005 Metric], ± 20%, X5R, CC Series"
			(at 0 0 90)
			(layer "F.Fab")
			(hide yes)
			(effects
				(font
					(size 1.27 1.27)
					(thickness 0.15)
				)
			)
		)
		(property "Author" "Antmicro"
			(at 332.889 -97.769 0)
			(layer "B.Fab")
			(hide yes)
			(effects
				(font
					(size 1 1)
					(thickness 0.15)
				)
				(justify mirror)
			)
		)
		(property "Dielectric" ""
			(at 332.889 -97.769 0)
			(layer "B.Fab")
			(hide yes)
			(effects
				(font
					(size 1 1)
					(thickness 0.15)
				)
				(justify mirror)
			)
		)
		(property "License" "Apache-2.0"
			(at 332.889 -97.769 0)
			(layer "B.Fab")
			(hide yes)
			(effects
				(font
					(size 1 1)
					(thickness 0.15)
				)
				(justify mirror)
			)
		)
		(property "MPN" "CC0402MRX5R5BB106"
			(at 332.889 -97.769 0)
			(layer "B.Fab")
			(hide yes)
			(effects
				(font
					(size 1 1)
					(thickness 0.15)
				)
				(justify mirror)
			)
		)
		(property "Manufacturer" "YAGEO"
			(at 332.889 -97.769 0)
			(layer "B.Fab")
			(hide yes)
			(effects
				(font
					(size 1 1)
					(thickness 0.15)
				)
				(justify mirror)
			)
		)
		(property "Public" ""
			(at 332.889 -97.769 0)
			(layer "B.Fab")
			(hide yes)
			(effects
				(font
					(size 1 1)
					(thickness 0.15)
				)
				(justify mirror)
			)
		)
		(property "Val" "10u"
			(at 332.889 -97.769 0)
			(layer "B.Fab")
			(hide yes)
			(effects
				(font
					(size 1 1)
					(thickness 0.15)
				)
				(justify mirror)
			)
		)
		(property "Voltage" ""
			(at 332.889 -97.769 0)
			(layer "B.Fab")
			(hide yes)
			(effects
				(font
					(size 1 1)
					(thickness 0.15)
				)
				(justify mirror)
			)
		)
		(sheetname "/Ethernet/")
		(sheetfile "ethernet.kicad_sch")
		(attr smd)
		(fp_rect
			(start -0.925 0.47)
			(end 0.925 -0.47)
			(stroke
				(width 0.05)
				(type default)
			)
			(fill no)
			(layer "B.CrtYd")
		)
		(fp_line
			(start 0.504 -0.248)
			(end -0.494 -0.248)
			(stroke
				(width 0.15)
				(type solid)
			)
			(layer "B.Fab")
		)
		(fp_line
			(start -0.494 -0.248)
			(end -0.494 0.25)
			(stroke
				(width 0.15)
				(type solid)
			)
			(layer "B.Fab")
		)
		(fp_line
			(start 0.504 0.25)
			(end 0.504 -0.248)
			(stroke
				(width 0.15)
				(type solid)
			)
			(layer "B.Fab")
		)
		(fp_line
			(start -0.494 0.25)
			(end 0.504 0.25)
			(stroke
				(width 0.15)
				(type solid)
			)
			(layer "B.Fab")
		)
		(fp_text user "Author: Antmicro"
			(at -0.939 -3.399 270)
			(layer "B.Fab")
			(effects
				(font
					(size 0.7 0.7)
					(thickness 0.15)
				)
				(justify left bottom mirror)
			)
		)
		(fp_text user "License: Apache-2.0"
			(at -0.939 -5.799 270)
			(layer "B.Fab")
			(effects
				(font
					(size 0.7 0.7)
					(thickness 0.15)
				)
				(justify left bottom mirror)
			)
		)
		(fp_text user "${REFERENCE}"
			(at -0.939 -4.599 270)
			(layer "B.Fab")
			(effects
				(font
					(size 0.7 0.7)
					(thickness 0.15)
				)
				(justify left bottom mirror)
			)
		)
		(pad "1" smd roundrect
			(at -0.48 0 90)
			(size 0.59 0.64)
			(layers "B.Cu" "B.Mask" "B.Paste")
			(roundrect_rratio 0.25)
			(net 417 "GND")
			(pintype "passive")
		)
		(pad "2" smd roundrect
			(at 0.48 0 90)
			(size 0.59 0.64)
			(layers "B.Cu" "B.Mask" "B.Paste")
			(roundrect_rratio 0.25)
			(net 50 "+3V3")
			(pintype "passive")
		)
	)
)
